(kicad_pcb
	(version 20260206)
	(generator "pcbnew")
	(generator_version "10.0")
	(general
		(thickness 1.21888)
		(legacy_teardrops no)
	)
	(paper "A4")
	(title_block
		(title "timecard-v9 — TimeCard-DC-V9_EXP.PcbDoc")
		(comment 1 "Time Appliance Project (Time Card) / footprints 18-24 of 402")
	)
	(layers
		(0 "F.Cu" signal "TOP")
		(4 "In1.Cu" signal "SGND")
		(6 "In2.Cu" signal "IN1")
		(8 "In3.Cu" signal "IN2")
		(10 "In4.Cu" signal "SGND1")
		(2 "B.Cu" signal "BOTTOM")
		(9 "F.Adhes" user "F.Adhesive")
		(11 "B.Adhes" user "B.Adhesive")
		(13 "F.Paste" user "Top Paste")
		(15 "B.Paste" user "Bottom Paste")
		(5 "F.SilkS" user "Top Overlay")
		(7 "B.SilkS" user "Bottom Overlay")
		(1 "F.Mask" user "Top Solder")
		(3 "B.Mask" user "Bottom Solder")
		(17 "Dwgs.User" user "User.Drawings")
		(19 "Cmts.User" user "User.Comments")
		(21 "Eco1.User" user "User.Eco1")
		(23 "Eco2.User" user "User.Eco2")
		(25 "Edge.Cuts" user)
		(27 "Margin" user)
		(31 "F.CrtYd" user "Top Courtyard")
		(29 "B.CrtYd" user "Bottom Courtyard")
		(35 "F.Fab" user "Top Component Center")
		(33 "B.Fab" user "Bottom Component Center")
	)
	(footprint "Connectors:PCIE_4LANE_EDGE"
		(layer "F.Cu")
		(at 127.02147 154.3547)
		(property "Reference" "P2"
			(at -12.64987 -0.282755 0)
			(unlocked yes)
			(layer "F.SilkS")
			(hide yes)
			(effects
				(font
					(size 0.762 0.762)
					(thickness 0.2286)
				)
				(justify left bottom)
			)
		)
		(property "Value" "PCIex4"
			(at -5.44907 18.557875 0)
			(unlocked yes)
			(layer "F.SilkS")
			(hide yes)
			(effects
				(font
					(size 0.762 0.762)
					(thickness 0.2286)
				)
				(justify left bottom)
			)
		)
		(sheetname "04-PCIe_JTAG")
		(sheetfile "04-PCIe_JTAG.kicad_sch")
		(duplicate_pad_numbers_are_jumpers no)
		(pad "A1" smd rect
			(at -16.49984 2.2286)
			(size 0.7112 3.2004)
			(layers "B.Cu" "B.Mask" "B.Paste")
			(net "PRSNT")
		)
		(pad "A2" smd rect
			(at -15.49985 2.7239)
			(size 0.7112 4.191)
			(layers "B.Cu" "B.Mask" "B.Paste")
			(net "+12V_PCIE")
		)
		(pad "A3" smd rect
			(at -14.49985 2.7239)
			(size 0.7112 4.191)
			(layers "B.Cu" "B.Mask" "B.Paste")
			(net "+12V_PCIE")
		)
		(pad "A4" smd rect
			(at -13.49985 2.7239)
			(size 0.7112 4.191)
			(layers "B.Cu" "B.Mask" "B.Paste")
			(net "GND")
		)
		(pad "A5" smd rect
			(at -12.49985 2.7239)
			(size 0.7112 4.191)
			(layers "B.Cu" "B.Mask" "B.Paste")
		)
		(pad "A6" smd rect
			(at -11.49985 2.7239)
			(size 0.7112 4.191)
			(layers "B.Cu" "B.Mask" "B.Paste")
		)
		(pad "A7" smd rect
			(at -10.49986 2.7239)
			(size 0.7112 4.191)
			(layers "B.Cu" "B.Mask" "B.Paste")
		)
		(pad "A8" smd rect
			(at -9.49986 2.7239)
			(size 0.7112 4.191)
			(layers "B.Cu" "B.Mask" "B.Paste")
		)
		(pad "A9" smd rect
			(at -8.49986 2.7239)
			(size 0.7112 4.191)
			(layers "B.Cu" "B.Mask" "B.Paste")
			(net "+3.3V_PCIE")
		)
		(pad "A10" smd rect
			(at -7.49986 2.7239)
			(size 0.7112 4.191)
			(layers "B.Cu" "B.Mask" "B.Paste")
			(net "+3.3V_PCIE")
		)
		(pad "A11" smd rect
			(at -6.49986 2.7239)
			(size 0.7112 4.191)
			(layers "B.Cu" "B.Mask" "B.Paste")
			(net "PCIE_PERST")
		)
		(pad "A12" smd rect
			(at -3.49987 2.7239)
			(size 0.7112 4.191)
			(layers "B.Cu" "B.Mask" "B.Paste")
			(net "GND")
		)
		(pad "A13" smd rect
			(at -2.49987 2.7239)
			(size 0.7112 4.191)
			(layers "B.Cu" "B.Mask" "B.Paste")
			(net "NetC44_1")
		)
		(pad "A14" smd rect
			(at -1.49987 2.7239)
			(size 0.7112 4.191)
			(layers "B.Cu" "B.Mask" "B.Paste")
			(net "NetC45_1")
		)
		(pad "A15" smd rect
			(at -0.49988 2.7239)
			(size 0.7112 4.191)
			(layers "B.Cu" "B.Mask" "B.Paste")
			(net "GND")
		)
		(pad "A16" smd rect
			(at 0.50012 2.7239)
			(size 0.7112 4.191)
			(layers "B.Cu" "B.Mask" "B.Paste")
			(net "NetC46_1")
		)
		(pad "A17" smd rect
			(at 1.50012 2.7239)
			(size 0.7112 4.191)
			(layers "B.Cu" "B.Mask" "B.Paste")
			(net "NetC47_1")
		)
		(pad "A18" smd rect
			(at 2.50012 2.7239)
			(size 0.7112 4.191)
			(layers "B.Cu" "B.Mask" "B.Paste")
			(net "GND")
		)
		(pad "A19" smd rect
			(at 3.50012 2.7239)
			(size 0.7112 4.191)
			(layers "B.Cu" "B.Mask" "B.Paste")
		)
		(pad "A20" smd rect
			(at 4.50011 2.7239)
			(size 0.7112 4.191)
			(layers "B.Cu" "B.Mask" "B.Paste")
			(net "GND")
		)
		(pad "A21" smd rect
			(at 5.50011 2.7239)
			(size 0.7112 4.191)
			(layers "B.Cu" "B.Mask" "B.Paste")
			(net "NetC48_1")
		)
		(pad "A22" smd rect
			(at 6.50011 2.7239)
			(size 0.7112 4.191)
			(layers "B.Cu" "B.Mask" "B.Paste")
			(net "NetC49_1")
		)
		(pad "A23" smd rect
			(at 7.50011 2.7239)
			(size 0.7112 4.191)
			(layers "B.Cu" "B.Mask" "B.Paste")
			(net "GND")
		)
		(pad "A24" smd rect
			(at 8.50011 2.7239)
			(size 0.7112 4.191)
			(layers "B.Cu" "B.Mask" "B.Paste")
			(net "GND")
		)
		(pad "A25" smd rect
			(at 9.5001 2.7239)
			(size 0.7112 4.191)
			(layers "B.Cu" "B.Mask" "B.Paste")
			(net "NetC50_1")
		)
		(pad "A26" smd rect
			(at 10.5001 2.7239)
			(size 0.7112 4.191)
			(layers "B.Cu" "B.Mask" "B.Paste")
			(net "NetC51_1")
		)
		(pad "A27" smd rect
			(at 11.5001 2.7239)
			(size 0.7112 4.191)
			(layers "B.Cu" "B.Mask" "B.Paste")
			(net "GND")
		)
		(pad "A28" smd rect
			(at 12.5001 2.7239)
			(size 0.7112 4.191)
			(layers "B.Cu" "B.Mask" "B.Paste")
			(net "GND")
		)
		(pad "A29" smd rect
			(at 13.5001 2.7239)
			(size 0.7112 4.191)
			(layers "B.Cu" "B.Mask" "B.Paste")
			(net "NetC52_1")
		)
		(pad "A30" smd rect
			(at 14.50009 2.7239)
			(size 0.7112 4.191)
			(layers "B.Cu" "B.Mask" "B.Paste")
			(net "NetC53_1")
		)
		(pad "A31" smd rect
			(at 15.50009 2.7239)
			(size 0.7112 4.191)
			(layers "B.Cu" "B.Mask" "B.Paste")
			(net "GND")
		)
		(pad "A32" smd rect
			(at 16.50009 2.7239)
			(size 0.7112 4.191)
			(layers "B.Cu" "B.Mask" "B.Paste")
		)
		(pad "B1" smd rect
			(at -16.49984 2.7239)
			(size 0.7112 4.191)
			(layers "F.Cu" "F.Mask" "F.Paste")
			(net "+12V_PCIE")
		)
		(pad "B2" smd rect
			(at -15.49985 2.7239)
			(size 0.7112 4.191)
			(layers "F.Cu" "F.Mask" "F.Paste")
			(net "+12V_PCIE")
		)
		(pad "B3" smd rect
			(at -14.49985 2.7239)
			(size 0.7112 4.191)
			(layers "F.Cu" "F.Mask" "F.Paste")
			(net "+12V_PCIE")
		)
		(pad "B4" smd rect
			(at -13.49985 2.7239)
			(size 0.7112 4.191)
			(layers "F.Cu" "F.Mask" "F.Paste")
			(net "GND")
		)
		(pad "B5" smd rect
			(at -12.49985 2.7239)
			(size 0.7112 4.191)
			(layers "F.Cu" "F.Mask" "F.Paste")
		)
		(pad "B6" smd rect
			(at -11.49985 2.7239)
			(size 0.7112 4.191)
			(layers "F.Cu" "F.Mask" "F.Paste")
		)
		(pad "B7" smd rect
			(at -10.49986 2.7239)
			(size 0.7112 4.191)
			(layers "F.Cu" "F.Mask" "F.Paste")
			(net "GND")
		)
		(pad "B8" smd rect
			(at -9.49986 2.7239)
			(size 0.7112 4.191)
			(layers "F.Cu" "F.Mask" "F.Paste")
			(net "+3.3V_PCIE")
		)
		(pad "B9" smd rect
			(at -8.49986 2.7239)
			(size 0.7112 4.191)
			(layers "F.Cu" "F.Mask" "F.Paste")
		)
		(pad "B10" smd rect
			(at -7.49986 2.7239)
			(size 0.7112 4.191)
			(layers "F.Cu" "F.Mask" "F.Paste")
		)
		(pad "B11" smd rect
			(at -6.49986 2.7239)
			(size 0.7112 4.191)
			(layers "F.Cu" "F.Mask" "F.Paste")
		)
		(pad "B12" smd rect
			(at -3.49987 2.7239)
			(size 0.7112 4.191)
			(layers "F.Cu" "F.Mask" "F.Paste")
		)
		(pad "B13" smd rect
			(at -2.49987 2.7239)
			(size 0.7112 4.191)
			(layers "F.Cu" "F.Mask" "F.Paste")
			(net "GND")
		)
		(pad "B14" smd rect
			(at -1.49987 2.7239)
			(size 0.7112 4.191)
			(layers "F.Cu" "F.Mask" "F.Paste")
			(net "PCIE_RX0_P")
		)
		(pad "B15" smd rect
			(at -0.49988 2.7239)
			(size 0.7112 4.191)
			(layers "F.Cu" "F.Mask" "F.Paste")
			(net "PCIE_RX0_N")
		)
		(pad "B16" smd rect
			(at 0.50012 2.7239)
			(size 0.7112 4.191)
			(layers "F.Cu" "F.Mask" "F.Paste")
			(net "GND")
		)
		(pad "B17" smd rect
			(at 1.50012 2.7239)
			(size 0.7112 4.191)
			(layers "F.Cu" "F.Mask" "F.Paste")
			(net "NetP2_B17")
		)
		(pad "B18" smd rect
			(at 2.50012 2.7239)
			(size 0.7112 4.191)
			(layers "F.Cu" "F.Mask" "F.Paste")
			(net "GND")
		)
		(pad "B19" smd rect
			(at 3.50012 2.7239)
			(size 0.7112 4.191)
			(layers "F.Cu" "F.Mask" "F.Paste")
			(net "PCIE_RX1_P")
		)
		(pad "B20" smd rect
			(at 4.50011 2.7239)
			(size 0.7112 4.191)
			(layers "F.Cu" "F.Mask" "F.Paste")
			(net "PCIE_RX1_N")
		)
		(pad "B21" smd rect
			(at 5.50011 2.7239)
			(size 0.7112 4.191)
			(layers "F.Cu" "F.Mask" "F.Paste")
			(net "GND")
		)
		(pad "B22" smd rect
			(at 6.50011 2.7239)
			(size 0.7112 4.191)
			(layers "F.Cu" "F.Mask" "F.Paste")
			(net "GND")
		)
		(pad "B23" smd rect
			(at 7.50011 2.7239)
			(size 0.7112 4.191)
			(layers "F.Cu" "F.Mask" "F.Paste")
			(net "PCIE_RX2_P")
		)
		(pad "B24" smd rect
			(at 8.50011 2.7239)
			(size 0.7112 4.191)
			(layers "F.Cu" "F.Mask" "F.Paste")
			(net "PCIE_RX2_N")
		)
		(pad "B25" smd rect
			(at 9.5001 2.7239)
			(size 0.7112 4.191)
			(layers "F.Cu" "F.Mask" "F.Paste")
			(net "GND")
		)
		(pad "B26" smd rect
			(at 10.5001 2.7239)
			(size 0.7112 4.191)
			(layers "F.Cu" "F.Mask" "F.Paste")
			(net "GND")
		)
		(pad "B27" smd rect
			(at 11.5001 2.7239)
			(size 0.7112 4.191)
			(layers "F.Cu" "F.Mask" "F.Paste")
			(net "PCIE_RX3_P")
		)
		(pad "B28" smd rect
			(at 12.5001 2.7239)
			(size 0.7112 4.191)
			(layers "F.Cu" "F.Mask" "F.Paste")
			(net "PCIE_RX3_N")
		)
		(pad "B29" smd rect
			(at 13.5001 2.7239)
			(size 0.7112 4.191)
			(layers "F.Cu" "F.Mask" "F.Paste")
			(net "GND")
		)
		(pad "B30" smd rect
			(at 14.50009 2.7239)
			(size 0.7112 4.191)
			(layers "F.Cu" "F.Mask" "F.Paste")
		)
		(pad "B31" smd rect
			(at 15.50009 2.2286)
			(size 0.7112 3.2004)
			(layers "F.Cu" "F.Mask" "F.Paste")
			(net "NetP2_B31")
		)
		(pad "B32" smd rect
			(at 16.50009 2.7239)
			(size 0.7112 4.191)
			(layers "F.Cu" "F.Mask" "F.Paste")
			(net "GND")
		)
	)
	(footprint "Vault:FP-BLM18-0_15-t0_8-IPC_A"
		(layer "F.Cu")
		(at 225.1216 131.3162)
		(property "Reference" "FB1"
			(at -3.271395 0.126921 0)
			(unlocked yes)
			(layer "F.SilkS")
			(effects
				(font
					(size 0.762 0.762)
					(thickness 0.2286)
				)
			)
		)
		(property "Value" "600ohm_1.3A_0603"
			(at 10.14352 2.744951 0)
			(unlocked yes)
			(layer "F.SilkS")
			(hide yes)
			(effects
				(font
					(size 0.762 0.762)
					(thickness 0.2286)
				)
			)
		)
		(sheetname "09-USBUart_PPSMUX_UARTMUX")
		(sheetfile "09-USBUart_PPSMUX_UARTMUX.kicad_sch")
		(duplicate_pad_numbers_are_jumpers no)
		(fp_line
			(start -1.42911 -0.92911)
			(end 1.42911 -0.92911)
			(stroke
				(width 0.2)
				(type solid)
			)
			(layer "F.SilkS")
		)
		(fp_line
			(start -1.42911 0.92911)
			(end 1.42911 0.92911)
			(stroke
				(width 0.2)
				(type solid)
			)
			(layer "F.SilkS")
		)
		(fp_line
			(start -1.92911 -1.02911)
			(end 1.92911 -1.02911)
			(stroke
				(width 0.2)
				(type solid)
			)
			(layer "F.CrtYd")
		)
		(fp_line
			(start -1.92911 1.02911)
			(end -1.92911 -1.02911)
			(stroke
				(width 0.2)
				(type solid)
			)
			(layer "F.CrtYd")
		)
		(fp_line
			(start -1.92911 1.02911)
			(end 1.92911 1.02911)
			(stroke
				(width 0.2)
				(type solid)
			)
			(layer "F.CrtYd")
		)
		(fp_line
			(start 1.92911 1.02911)
			(end 1.92911 -1.02911)
			(stroke
				(width 0.2)
				(type solid)
			)
			(layer "F.CrtYd")
		)
		(fp_line
			(start -1.92911 -1.02911)
			(end 1.92911 -1.02911)
			(stroke
				(width 0.2)
				(type solid)
			)
			(layer "F.Fab")
		)
		(fp_line
			(start -1.92911 1.02911)
			(end -1.92911 -1.02911)
			(stroke
				(width 0.2)
				(type solid)
			)
			(layer "F.Fab")
		)
		(fp_line
			(start -1.92911 1.02911)
			(end 1.92911 1.02911)
			(stroke
				(width 0.2)
				(type solid)
			)
			(layer "F.Fab")
		)
		(fp_line
			(start -0.5 0)
			(end 0.5 0)
			(stroke
				(width 0.1)
				(type solid)
			)
			(layer "F.Fab")
		)
		(fp_line
			(start 0 0.5)
			(end 0 -0.5)
			(stroke
				(width 0.1)
				(type solid)
			)
			(layer "F.Fab")
		)
		(fp_line
			(start 1.92911 1.02911)
			(end 1.92911 -1.02911)
			(stroke
				(width 0.2)
				(type solid)
			)
			(layer "F.Fab")
		)
		(fp_text user "${REFERENCE}"
			(at -0.00001 0.10711 360)
			(unlocked yes)
			(layer "F.Fab")
			(effects
				(font
					(face "Arial")
					(size 0.63 0.63)
					(thickness 0.1)
				)
				(justify left bottom)
			)
		)
		(pad "1" smd rect
			(at -0.77608 0)
			(size 1.30606 1.05822)
			(layers "F.Cu" "F.Mask" "F.Paste")
			(net "USB_VBUS")
			(solder_mask_margin 0)
			(solder_paste_margin 0)
		)
		(pad "2" smd rect
			(at 0.77608 0)
			(size 1.30606 1.05822)
			(layers "F.Cu" "F.Mask" "F.Paste")
			(net "FTDI_VBUS")
			(solder_mask_margin 0)
			(solder_paste_margin 0)
		)
	)
	(footprint "Vault:RESC1005X40X25LL05T05"
		(layer "F.Cu")
		(at 211.9216 131.5162 180)
		(property "Reference" "R139"
			(at -5.2032 -0.126921 0)
			(unlocked yes)
			(layer "F.SilkS")
			(effects
				(font
					(size 0.762 0.762)
					(thickness 0.2032)
				)
			)
		)
		(property "Value" "0_1%_0402"
			(at -2.579871 6.63996 90)
			(unlocked yes)
			(layer "F.SilkS")
			(hide yes)
			(effects
				(font
					(size 0.762 0.762)
					(thickness 0.2032)
				)
			)
		)
		(sheetname "10-M2_GPS")
		(sheetfile "10-M2_GPS.kicad_sch")
		(duplicate_pad_numbers_are_jumpers no)
		(pad "1" smd rect
			(at -0.4 0 270)
			(size 0.45 0.45)
			(layers "F.Cu" "F.Mask" "F.Paste")
			(net "NetJ45_46")
		)
		(pad "2" smd rect
			(at 0.4 0 270)
			(size 0.45 0.45)
			(layers "F.Cu" "F.Mask" "F.Paste")
			(net "M2_GPS2_TP1")
		)
	)
	(footprint "Vault:RESC1005X40X25NL10T10"
		(layer "F.Cu")
		(at 78.4216 104.0162)
		(property "Reference" "R14"
			(at 0.6286 1.026921 0)
			(unlocked yes)
			(layer "F.SilkS")
			(effects
				(font
					(size 0.762 0.762)
					(thickness 0.2286)
				)
			)
		)
		(property "Value" "4.7K_1%_0402"
			(at 7.110135 5.008471 0)
			(unlocked yes)
			(layer "F.SilkS")
			(hide yes)
			(effects
				(font
					(size 0.762 0.762)
					(thickness 0.2286)
				)
			)
		)
		(sheetname "01-USER_IO")
		(sheetfile "01-USER_IO.kicad_sch")
		(duplicate_pad_numbers_are_jumpers no)
		(pad "1" smd rect
			(at -0.425 0 90)
			(size 0.6 0.65)
			(layers "F.Cu" "F.Mask" "F.Paste")
			(net "+3.3V")
		)
		(pad "2" smd rect
			(at 0.425 0 90)
			(size 0.6 0.65)
			(layers "F.Cu" "F.Mask" "F.Paste")
			(net "ANT1_IO_OUT")
		)
	)
	(footprint "Vault:RESC1005X40X25NL05T05"
		(layer "F.Cu")
		(at 113.4216 58.0162 -90)
		(property "Reference" "R159"
			(at 2.5032 -0.173069 270)
			(unlocked yes)
			(layer "F.SilkS")
			(effects
				(font
					(size 0.762 0.762)
					(thickness 0.2032)
				)
			)
		)
		(property "Value" "DNI_27_1%_0402"
			(at -2.732271 10.270975 180)
			(unlocked yes)
			(layer "F.SilkS")
			(hide yes)
			(effects
				(font
					(size 0.762 0.762)
					(thickness 0.2032)
				)
			)
		)
		(sheetname "11-M2_RCB_MUX")
		(sheetfile "11-M2_RCB_MUX.kicad_sch")
		(duplicate_pad_numbers_are_jumpers no)
		(pad "1" smd rect
			(at -0.45 0)
			(size 0.55 0.55)
			(layers "F.Cu" "F.Mask" "F.Paste")
			(net "RCB_GPS1_TP1")
		)
		(pad "2" smd rect
			(at 0.45 0)
			(size 0.55 0.55)
			(layers "F.Cu" "F.Mask" "F.Paste")
			(net "GPS1_TP1")
		)
	)
	(footprint "Vault:FP-ERJ2RK-IPC_A"
		(layer "F.Cu")
		(at 96.32159 80.4162)
		(property "Reference" "R1"
			(at -3.09999 0.493345 0)
			(unlocked yes)
			(layer "F.SilkS")
			(effects
				(font
					(size 0.762 0.762)
					(thickness 0.2286)
				)
				(justify left bottom)
			)
		)
		(property "Value" "200_1%_0402"
			(at -17.19089 9.390245 0)
			(unlocked yes)
			(layer "F.SilkS")
			(hide yes)
			(effects
				(font
					(size 0.762 0.762)
					(thickness 0.2286)
				)
				(justify left bottom)
			)
		)
		(sheetname "03-POWER")
		(sheetfile "03-POWER.kicad_sch")
		(duplicate_pad_numbers_are_jumpers no)
		(fp_line
			(start -0.83623 -0.73624)
			(end 0.83624 -0.73624)
			(stroke
				(width 0.2)
				(type solid)
			)
			(layer "F.SilkS")
		)
		(fp_line
			(start -0.83623 0.73624)
			(end 0.83624 0.73624)
			(stroke
				(width 0.2)
				(type solid)
			)
			(layer "F.SilkS")
		)
		(fp_line
			(start -1.03623 -0.53624)
			(end 1.03624 -0.53624)
			(stroke
				(width 0.2)
				(type solid)
			)
			(layer "F.CrtYd")
		)
		(fp_line
			(start -1.03623 0.53624)
			(end -1.03623 -0.53624)
			(stroke
				(width 0.2)
				(type solid)
			)
			(layer "F.CrtYd")
		)
		(fp_line
			(start -1.03623 0.53624)
			(end 1.03624 0.53624)
			(stroke
				(width 0.2)
				(type solid)
			)
			(layer "F.CrtYd")
		)
		(fp_line
			(start 1.03624 0.53624)
			(end 1.03624 -0.53624)
			(stroke
				(width 0.2)
				(type solid)
			)
			(layer "F.CrtYd")
		)
		(fp_line
			(start -1.03623 -0.53624)
			(end 1.03624 -0.53624)
			(stroke
				(width 0.2)
				(type solid)
			)
			(layer "F.Fab")
		)
		(fp_line
			(start -1.03623 0.53624)
			(end -1.03623 -0.53624)
			(stroke
				(width 0.2)
				(type solid)
			)
			(layer "F.Fab")
		)
		(fp_line
			(start -1.03623 0.53624)
			(end 1.03624 0.53624)
			(stroke
				(width 0.2)
				(type solid)
			)
			(layer "F.Fab")
		)
		(fp_line
			(start -0.5 0)
			(end 0.5 0)
			(stroke
				(width 0.1)
				(type solid)
			)
			(layer "F.Fab")
		)
		(fp_line
			(start 0 0.5)
			(end 0 -0.5)
			(stroke
				(width 0.1)
				(type solid)
			)
			(layer "F.Fab")
		)
		(fp_line
			(start 1.03624 0.53624)
			(end 1.03624 -0.53624)
			(stroke
				(width 0.2)
				(type solid)
			)
			(layer "F.Fab")
		)
		(fp_text user "${REFERENCE}"
			(at -0.00001 0.10711 360)
			(unlocked yes)
			(layer "F.Fab")
			(effects
				(font
					(face "Arial")
					(size 0.63 0.63)
					(thickness 0.1)
				)
				(justify left bottom)
			)
		)
		(pad "1" smd rect
			(at -0.50214 0)
			(size 0.66818 0.67248)
			(layers "F.Cu" "F.Mask" "F.Paste")
			(net "GND")
			(solder_mask_margin 0)
			(solder_paste_margin 0)
		)
		(pad "2" smd rect
			(at 0.50215 0)
			(size 0.66818 0.67248)
			(layers "F.Cu" "F.Mask" "F.Paste")
			(net "NetD4_1")
			(solder_mask_margin 0)
			(solder_paste_margin 0)
		)
	)
	(footprint "Vault:RESC1005X40X25NL05T05"
		(layer "F.Cu")
		(at 156.7216 127.3162 -90)
		(property "Reference" "R85"
			(at -2.0714 0.026931 270)
			(unlocked yes)
			(layer "F.SilkS")
			(effects
				(font
					(size 0.762 0.762)
					(thickness 0.2286)
				)
			)
		)
		(property "Value" "27_1%_0402"
			(at -2.732271 7.37632 180)
			(unlocked yes)
			(layer "F.SilkS")
			(hide yes)
			(effects
				(font
					(size 0.762 0.762)
					(thickness 0.2286)
				)
			)
		)
		(sheetname "09-USBUart_PPSMUX_UARTMUX")
		(sheetfile "09-USBUart_PPSMUX_UARTMUX.kicad_sch")
		(duplicate_pad_numbers_are_jumpers no)
		(pad "1" smd rect
			(at -0.45 0)
			(size 0.55 0.55)
			(layers "F.Cu" "F.Mask" "F.Paste")
			(net "FTDI_RX")
		)
		(pad "2" smd rect
			(at 0.45 0)
			(size 0.55 0.55)
			(layers "F.Cu" "F.Mask" "F.Paste")
			(net "NetR85_2")
		)
	)
)
